# BASEBOARD_FAB2 (Tioga Pass) — schematic netlist excerpt (pin names and nets, part order shuffled) for the footprints in the layout excerpt that follows; sources: Cadence DE-HDL packaged netlist, KiCad conversion of Wiwynn_Tioga_Pass_MB.brd

C5D29  CAP_A  22.0UF 4V 20% X6S  pkg 0603V  page 42 : A = PVCCIN_CPU0 ; B = GND
C7B29  CAP  0.22UF 16V 10% X7R  pkg 0402  page 129 : A = DMI_CPU0_PCH_TX_DN<2> ; B = DMI_CPU0_PCH_TX_C_DN<2>
R2T43  RES  75 1.0% CHIP  pkg 0402  page 92 : A = H_CPU_ERR2_G_R_N ; B = H_CPU_ERR2_GTL_N

(kicad_pcb
	(version 20260206)
	(generator "pcbnew")
	(generator_version "10.0")
	(general
		(thickness 1.6)
		(legacy_teardrops no)
	)
	(paper "A4")
	(title_block
		(title "Wiwynn_Tioga_Pass_MB.brd")
		(comment 1 "Tioga Pass / footprints 921-923 of 4770")
	)
	(layers
		(0 "F.Cu" signal "TOP")
		(4 "In1.Cu" signal "L2GND")
		(6 "In2.Cu" signal "L3")
		(8 "In3.Cu" signal "L4GND")
		(10 "In4.Cu" signal "L5")
		(12 "In5.Cu" signal "L6GND")
		(14 "In6.Cu" signal "L7VCC")
		(16 "In7.Cu" signal "L8VCC")
		(18 "In8.Cu" signal "L9GND")
		(20 "In9.Cu" signal "L10")
		(22 "In10.Cu" signal "L11GND")
		(24 "In11.Cu" signal "L12")
		(26 "In12.Cu" signal "L13GND")
		(2 "B.Cu" signal "BOTTOM")
		(9 "F.Adhes" user "F.Adhesive")
		(11 "B.Adhes" user "B.Adhesive")
		(13 "F.Paste" user "Package Geometry/Pastemask Top")
		(15 "B.Paste" user "Package Geometry/Pastemask Bottom")
		(5 "F.SilkS" user "Ref Des/Silkscreen Top")
		(7 "B.SilkS" user "Ref Des/Silkscreen Bottom")
		(1 "F.Mask" user "Board Geometry/Soldermask Top")
		(3 "B.Mask" user "Board Geometry/Soldermask Bottom")
		(17 "Dwgs.User" user "User.Drawings")
		(19 "Cmts.User" user "User.Comments")
		(21 "Eco1.User" user "User.Eco1")
		(23 "Eco2.User" user "User.Eco2")
		(25 "Edge.Cuts" user "Board Geometry/Outline")
		(27 "Margin" user)
		(31 "F.CrtYd" user "Package Geometry/Place Bound Top")
		(29 "B.CrtYd" user "Package Geometry/Place Bound Bottom")
		(35 "F.Fab" user "Ref Des/Assembly Top")
		(33 "B.Fab" user "Ref Des/Assembly Bottom")
	)
	(footprint ""
		(layer "F.Cu")
		(at 384.422904 -76.915264)
		(property "Reference" "R2T43"
			(at 0 0 0)
			(layer "F.SilkS")
			(hide yes)
			(effects
				(font
					(size 1.27 1.27)
				)
			)
		)
		(property "Value" ""
			(at 0 0 0)
			(layer "F.Fab")
			(effects
				(font
					(size 1.27 1.27)
				)
			)
		)
		(duplicate_pad_numbers_are_jumpers no)
		(fp_poly
			(pts
				(xy -0.2794 -0.1016) (xy 0.2794 -0.1016) (xy 0.2794 0.9906) (xy -0.2794 0.9906)
			)
			(stroke
				(width 0)
				(type default)
			)
			(fill no)
			(layer "F.CrtYd")
		)
		(fp_line
			(start -0.2794 -0.1016)
			(end -0.2794 0.9906)
			(stroke
				(width 0.1)
				(type default)
			)
			(layer "F.Fab")
		)
		(fp_line
			(start -0.2794 0.9906)
			(end 0.2794 0.9906)
			(stroke
				(width 0.1)
				(type default)
			)
			(layer "F.Fab")
		)
		(fp_line
			(start 0.2794 -0.1016)
			(end -0.2794 -0.1016)
			(stroke
				(width 0.1)
				(type default)
			)
			(layer "F.Fab")
		)
		(fp_line
			(start 0.2794 0.9906)
			(end 0.2794 -0.1016)
			(stroke
				(width 0.1)
				(type default)
			)
			(layer "F.Fab")
		)
		(pad "1" smd rect
			(at 0 0)
			(size 0.508 0.508)
			(layers "F.Cu" "F.Mask" "F.Paste")
			(net "H_CPU_ERR2_G_R_N")
		)
		(pad "2" smd rect
			(at 0 0.889)
			(size 0.508 0.508)
			(layers "F.Cu" "F.Mask" "F.Paste")
			(net "H_CPU_ERR2_GTL_N")
		)
		(zone
			(layer "F.Cu")
			(hatch none 0.5)
			(connect_pads
				(clearance 0)
			)
			(min_thickness 0.25)
			(keepout
				(tracks allowed)
				(vias not_allowed)
				(pads allowed)
				(copperpour not_allowed)
				(footprints allowed)
			)
			(placement
				(enabled no)
				(sheetname "")
			)
			(fill
				(thermal_gap 0.5)
				(thermal_bridge_width 0.5)
				(island_removal_mode 0)
			)
			(polygon
				(pts
					(xy 384.168904 -76.661264) (xy 384.676904 -76.661264) (xy 384.676904 -76.280264) (xy 384.168904 -76.280264)
				)
			)
		)
		(zone
			(layer "F.Cu")
			(hatch none 0.5)
			(connect_pads
				(clearance 0)
			)
			(min_thickness 0.25)
			(keepout
				(tracks not_allowed)
				(vias allowed)
				(pads allowed)
				(copperpour not_allowed)
				(footprints allowed)
			)
			(placement
				(enabled no)
				(sheetname "")
			)
			(fill
				(thermal_gap 0.5)
				(thermal_bridge_width 0.5)
				(island_removal_mode 0)
			)
			(polygon
				(pts
					(xy 384.168904 -76.280264) (xy 384.676904 -76.280264) (xy 384.676904 -76.661264) (xy 384.168904 -76.661264)
				)
			)
		)
	)
	(footprint ""
		(layer "F.Cu")
		(at 264.431272 -77.636116)
		(property "Reference" "C5D29"
			(at 0 0 0)
			(layer "F.SilkS")
			(hide yes)
			(effects
				(font
					(size 1.27 1.27)
				)
			)
		)
		(property "Value" ""
			(at 0 0 0)
			(layer "F.Fab")
			(effects
				(font
					(size 1.27 1.27)
				)
			)
		)
		(duplicate_pad_numbers_are_jumpers no)
		(fp_poly
			(pts
				(xy -0.4953 -0.2032) (xy 0.4953 -0.2032) (xy 0.4953 1.6002) (xy -0.4953 1.6002)
			)
			(stroke
				(width 0)
				(type default)
			)
			(fill no)
			(layer "F.CrtYd")
		)
		(fp_line
			(start -0.4953 -0.2032)
			(end 0.4953 -0.2032)
			(stroke
				(width 0.1)
				(type default)
			)
			(layer "F.Fab")
		)
		(fp_line
			(start -0.4953 1.6002)
			(end -0.4953 -0.2032)
			(stroke
				(width 0.1)
				(type default)
			)
			(layer "F.Fab")
		)
		(fp_line
			(start 0.4953 -0.2032)
			(end 0.4953 1.6002)
			(stroke
				(width 0.1)
				(type default)
			)
			(layer "F.Fab")
		)
		(fp_line
			(start 0.4953 1.6002)
			(end -0.4953 1.6002)
			(stroke
				(width 0.1)
				(type default)
			)
			(layer "F.Fab")
		)
		(pad "1" smd rect
			(at 0 0)
			(size 0.762 0.889)
			(layers "F.Cu" "F.Mask" "F.Paste")
			(net "PVCCIN_CPU0")
		)
		(pad "2" smd rect
			(at 0 1.397)
			(size 0.762 0.889)
			(layers "F.Cu" "F.Mask" "F.Paste")
			(net "GND")
		)
		(zone
			(layer "F.Cu")
			(hatch none 0.5)
			(connect_pads
				(clearance 0)
			)
			(min_thickness 0.25)
			(keepout
				(tracks not_allowed)
				(vias allowed)
				(pads allowed)
				(copperpour not_allowed)
				(footprints allowed)
			)
			(placement
				(enabled no)
				(sheetname "")
			)
			(fill
				(thermal_gap 0.5)
				(thermal_bridge_width 0.5)
				(island_removal_mode 0)
			)
			(polygon
				(pts
					(xy 264.050272 -77.191616) (xy 264.812272 -77.191616) (xy 264.812272 -76.683616) (xy 264.050272 -76.683616)
				)
			)
		)
	)
	(footprint ""
		(layer "F.Cu")
		(at 368.554 -112.395 90)
		(property "Reference" "C7B29"
			(at 0 0 90)
			(layer "F.SilkS")
			(hide yes)
			(effects
				(font
					(size 1.27 1.27)
				)
			)
		)
		(property "Value" ""
			(at 0 0 90)
			(layer "F.Fab")
			(effects
				(font
					(size 1.27 1.27)
				)
			)
		)
		(duplicate_pad_numbers_are_jumpers no)
		(fp_poly
			(pts
				(xy 0.3048 -0.1016) (xy 0.3048 0.9906) (xy -0.3048 0.9906) (xy -0.3048 -0.1016)
			)
			(stroke
				(width 0)
				(type default)
			)
			(fill no)
			(layer "F.CrtYd")
		)
		(fp_line
			(start 0.3048 -0.1016)
			(end -0.3048 -0.1016)
			(stroke
				(width 0.1)
				(type default)
			)
			(layer "F.Fab")
		)
		(fp_line
			(start -0.3048 -0.1016)
			(end -0.3048 0.9906)
			(stroke
				(width 0.1)
				(type default)
			)
			(layer "F.Fab")
		)
		(fp_line
			(start 0.3048 0.9906)
			(end 0.3048 -0.1016)
			(stroke
				(width 0.1)
				(type default)
			)
			(layer "F.Fab")
		)
		(fp_line
			(start -0.3048 0.9906)
			(end 0.3048 0.9906)
			(stroke
				(width 0.1)
				(type default)
			)
			(layer "F.Fab")
		)
		(pad "1" smd rect
			(at 0 0 90)
			(size 0.508 0.508)
			(layers "F.Cu" "F.Mask" "F.Paste")
			(net "DMI_CPU0_PCH_TX_DN<2>")
		)
		(pad "2" smd rect
			(at 0 0.889 90)
			(size 0.508 0.508)
			(layers "F.Cu" "F.Mask" "F.Paste")
			(net "DMI_CPU0_PCH_TX_C_DN<2>")
		)
		(zone
			(layer "F.Cu")
			(hatch none 0.5)
			(connect_pads
				(clearance 0)
			)
			(min_thickness 0.25)
			(keepout
				(tracks allowed)
				(vias not_allowed)
				(pads allowed)
				(copperpour not_allowed)
				(footprints allowed)
			)
			(placement
				(enabled no)
				(sheetname "")
			)
			(fill
				(thermal_gap 0.5)
				(thermal_bridge_width 0.5)
				(island_removal_mode 0)
			)
			(polygon
				(pts
					(xy 368.808 -112.141) (xy 368.808 -112.649) (xy 369.189 -112.649) (xy 369.189 -112.141)
				)
			)
		)
		(zone
			(layer "F.Cu")
			(hatch none 0.5)
			(connect_pads
				(clearance 0)
			)
			(min_thickness 0.25)
			(keepout
				(tracks not_allowed)
				(vias allowed)
				(pads allowed)
				(copperpour not_allowed)
				(footprints allowed)
			)
			(placement
				(enabled no)
				(sheetname "")
			)
			(fill
				(thermal_gap 0.5)
				(thermal_bridge_width 0.5)
				(island_removal_mode 0)
			)
			(polygon
				(pts
					(xy 369.189 -112.141) (xy 369.189 -112.649) (xy 368.808 -112.649) (xy 368.808 -112.141)
				)
			)
		)
	)
)
